(kicad_pcb
	(version 20260206)
	(generator "pcbnew")
	(generator_version "10.0")
	(general
		(thickness 1.6)
		(legacy_teardrops no)
	)
	(paper "A4")
	(title_block
		(title "baseboard — 13948-1b.1110WZS1818.brd")
		(comment 1 "Honey Badger (Wiwynn) / footprints 1669-1675 of 2523")
	)
	(layers
		(0 "F.Cu" signal "TOP")
		(4 "In1.Cu" signal "L2GND")
		(6 "In2.Cu" signal "L3")
		(8 "In3.Cu" signal "L4VCC")
		(10 "In4.Cu" signal "L5VCC")
		(12 "In5.Cu" signal "L6")
		(14 "In6.Cu" signal "L7GND")
		(2 "B.Cu" signal "BOTTOM")
		(9 "F.Adhes" user "F.Adhesive")
		(11 "B.Adhes" user "B.Adhesive")
		(13 "F.Paste" user "Package Geometry/Pastemask Top")
		(15 "B.Paste" user "Package Geometry/Pastemask Bottom")
		(5 "F.SilkS" user "Ref Des/Silkscreen Top")
		(7 "B.SilkS" user "Ref Des/Silkscreen Bottom")
		(1 "F.Mask" user "Board Geometry/Soldermask Top")
		(3 "B.Mask" user "Board Geometry/Soldermask Bottom")
		(17 "Dwgs.User" user "User.Drawings")
		(19 "Cmts.User" user "User.Comments")
		(21 "Eco1.User" user "User.Eco1")
		(23 "Eco2.User" user "User.Eco2")
		(25 "Edge.Cuts" user "Board Geometry/Outline")
		(27 "Margin" user)
		(31 "F.CrtYd" user "Package Geometry/Place Bound Top")
		(29 "B.CrtYd" user "Package Geometry/Place Bound Bottom")
		(35 "F.Fab" user "Ref Des/Assembly Top")
		(33 "B.Fab" user "Ref Des/Assembly Bottom")
	)
	(footprint ""
		(layer "F.Cu")
		(at 318.008 -162.306 -90)
		(property "Reference" "R307"
			(at 0 0 270)
			(layer "F.SilkS")
			(hide yes)
			(effects
				(font
					(size 1.27 1.27)
				)
			)
		)
		(property "Value" "10KR2F-2-GP"
			(at 0.064008 -3.993896 270)
			(unlocked yes)
			(layer "F.Fab")
			(hide yes)
			(effects
				(font
					(size 1.016 1.016)
					(thickness 0.1524)
				)
			)
		)
		(property "Device Type" "R402H16"
			(at 0.064008 -5.517896 270)
			(unlocked yes)
			(layer "F.Fab")
			(hide yes)
			(effects
				(font
					(size 1.016 1.016)
					(thickness 0.1524)
				)
			)
		)
		(duplicate_pad_numbers_are_jumpers no)
		(fp_line
			(start -0.508 -0.9398)
			(end -0.508 0.9398)
			(stroke
				(width 0.1524)
				(type default)
			)
			(layer "F.SilkS")
		)
		(fp_line
			(start 0.508 -0.9398)
			(end -0.508 -0.9398)
			(stroke
				(width 0.1524)
				(type default)
			)
			(layer "F.SilkS")
		)
		(fp_rect
			(start -0.508 0.9398)
			(end 0.508 -0.9398)
			(stroke
				(width 0)
				(type default)
			)
			(fill no)
			(layer "F.CrtYd")
		)
		(fp_rect
			(start -0.508 0.9398)
			(end 0.508 -0.9398)
			(stroke
				(width 0)
				(type default)
			)
			(fill no)
			(layer "F.Fab")
		)
		(pad "1" smd custom
			(at 0 -0.4445 270)
			(size 0.1397 0.1397)
			(layers "F.Cu" "F.Mask" "F.Paste")
			(net "P3V3_STBY")
			(options
				(clearance outline)
				(anchor circle)
			)
			(primitives
				(gr_poly
					(pts
						(arc
							(start -0.1778 -0.2794)
							(mid -0.249642 -0.249642)
							(end -0.2794 -0.1778)
						)
						(arc
							(start -0.2794 0.1778)
							(mid -0.249642 0.249642)
							(end -0.1778 0.2794)
						)
						(arc
							(start 0.1778 0.2794)
							(mid 0.249642 0.249642)
							(end 0.2794 0.1778)
						)
						(arc
							(start 0.2794 -0.1778)
							(mid 0.249642 -0.249642)
							(end 0.1778 -0.2794)
						)
					)
					(width 0)
					(fill yes)
				)
			)
		)
		(pad "2" smd custom
			(at 0 0.4445 270)
			(size 0.1397 0.1397)
			(layers "F.Cu" "F.Mask" "F.Paste")
			(net "PU_BMC0_SDA13")
			(options
				(clearance outline)
				(anchor circle)
			)
			(primitives
				(gr_poly
					(pts
						(arc
							(start -0.1778 -0.2794)
							(mid -0.249642 -0.249642)
							(end -0.2794 -0.1778)
						)
						(arc
							(start -0.2794 0.1778)
							(mid -0.249642 0.249642)
							(end -0.1778 0.2794)
						)
						(arc
							(start 0.1778 0.2794)
							(mid 0.249642 0.249642)
							(end 0.2794 0.1778)
						)
						(arc
							(start 0.2794 -0.1778)
							(mid 0.249642 -0.249642)
							(end 0.1778 -0.2794)
						)
					)
					(width 0)
					(fill yes)
				)
			)
		)
	)
	(footprint ""
		(layer "F.Cu")
		(at 278.003 -16.891 90)
		(property "Reference" "R446"
			(at 0 0 90)
			(layer "F.SilkS")
			(hide yes)
			(effects
				(font
					(size 1.27 1.27)
				)
			)
		)
		(property "Value" "0R3J-0-U-GP"
			(at -0.0254 -2.5146 90)
			(unlocked yes)
			(layer "F.Fab")
			(hide yes)
			(effects
				(font
					(size 1.016 1.016)
					(thickness 0.1524)
				)
			)
		)
		(property "Device Type" "R603H22"
			(at -0.0254 -4.0386 90)
			(unlocked yes)
			(layer "F.Fab")
			(hide yes)
			(effects
				(font
					(size 1.016 1.016)
					(thickness 0.1524)
				)
			)
		)
		(duplicate_pad_numbers_are_jumpers no)
		(fp_line
			(start 0.2032 0)
			(end 0.4826 0)
			(stroke
				(width 0.2032)
				(type default)
			)
			(layer "F.SilkS")
		)
		(fp_line
			(start -0.4826 0)
			(end -0.2032 0)
			(stroke
				(width 0.2032)
				(type default)
			)
			(layer "F.SilkS")
		)
		(fp_rect
			(start -0.5842 1.3335)
			(end 0.5842 -1.3335)
			(stroke
				(width 0)
				(type default)
			)
			(fill no)
			(layer "F.CrtYd")
		)
		(fp_rect
			(start -0.5842 1.3335)
			(end 0.5842 -1.3335)
			(stroke
				(width 0)
				(type default)
			)
			(fill no)
			(layer "F.Fab")
		)
		(pad "1" smd custom
			(at 0 -0.762 90)
			(size 0.2159 0.2159)
			(layers "F.Cu" "F.Mask" "F.Paste")
			(net "AGND_USB")
			(options
				(clearance outline)
				(anchor circle)
			)
			(primitives
				(gr_poly
					(pts
						(arc
							(start -0.3302 -0.4318)
							(mid -0.402042 -0.402042)
							(end -0.4318 -0.3302)
						)
						(arc
							(start -0.4318 0.3302)
							(mid -0.402042 0.402042)
							(end -0.3302 0.4318)
						)
						(arc
							(start 0.3302 0.4318)
							(mid 0.402042 0.402042)
							(end 0.4318 0.3302)
						)
						(arc
							(start 0.4318 -0.3302)
							(mid 0.402042 -0.402042)
							(end 0.3302 -0.4318)
						)
					)
					(width 0)
					(fill yes)
				)
			)
		)
		(pad "2" smd custom
			(at 0 0.762 90)
			(size 0.2159 0.2159)
			(layers "F.Cu" "F.Mask" "F.Paste")
			(net "GND")
			(options
				(clearance outline)
				(anchor circle)
			)
			(primitives
				(gr_poly
					(pts
						(arc
							(start -0.3302 -0.4318)
							(mid -0.402042 -0.402042)
							(end -0.4318 -0.3302)
						)
						(arc
							(start -0.4318 0.3302)
							(mid -0.402042 0.402042)
							(end -0.3302 0.4318)
						)
						(arc
							(start 0.3302 0.4318)
							(mid 0.402042 0.402042)
							(end 0.4318 0.3302)
						)
						(arc
							(start 0.4318 -0.3302)
							(mid 0.402042 -0.402042)
							(end 0.3302 -0.4318)
						)
					)
					(width 0)
					(fill yes)
				)
			)
		)
	)
	(footprint ""
		(layer "F.Cu")
		(at 86.976966 -84.328 180)
		(property "Reference" "SC1156"
			(at 0 0 180)
			(layer "F.SilkS")
			(hide yes)
			(effects
				(font
					(size 1.27 1.27)
				)
			)
		)
		(property "Value" "SC1U6D3V1MX-GP"
			(at 1.9177 2.0193 180)
			(unlocked yes)
			(layer "F.Fab")
			(hide yes)
			(effects
				(font
					(size 1.016 1.016)
					(thickness 0.1524)
				)
			)
		)
		(property "Device Type" "C0201H14"
			(at 1.9177 0.4953 180)
			(unlocked yes)
			(layer "F.Fab")
			(hide yes)
			(effects
				(font
					(size 1.016 1.016)
					(thickness 0.1524)
				)
			)
		)
		(duplicate_pad_numbers_are_jumpers no)
		(fp_rect
			(start -0.1524 0.3048)
			(end 0.1524 -0.3048)
			(stroke
				(width 0)
				(type default)
			)
			(fill no)
			(layer "F.CrtYd")
		)
		(fp_poly
			(pts
				(xy -0.2794 0.6477) (xy -0.2794 -0.6477) (xy 0.2794 -0.6477) (xy 0.2794 -0.1905) (xy 0.1524 -0.1905)
				(xy 0.1524 -0.3048) (xy -0.1524 -0.3048) (xy -0.1524 0.3048) (xy 0.1524 0.3048) (xy 0.1524 -0.1778)
				(xy 0.2794 -0.1778) (xy 0.2794 0.6477)
			)
			(stroke
				(width 0)
				(type default)
			)
			(fill no)
			(layer "F.CrtYd")
		)
		(fp_rect
			(start -0.2794 0.6477)
			(end 0.2794 -0.6477)
			(stroke
				(width 0)
				(type default)
			)
			(fill no)
			(layer "F.Fab")
		)
		(pad "1" smd custom
			(at 0 -0.2794 180)
			(size 0.0762 0.0762)
			(layers "F.Cu" "F.Mask" "F.Paste")
			(net "PLLDDR_VDDA18")
			(options
				(clearance outline)
				(anchor circle)
			)
			(primitives
				(gr_poly
					(pts
						(arc
							(start 0.1524 -0.127)
							(mid 0.137521 -0.162921)
							(end 0.1016 -0.1778)
						)
						(arc
							(start -0.1016 -0.1778)
							(mid -0.137521 -0.162921)
							(end -0.1524 -0.127)
						)
						(arc
							(start -0.1524 0.127)
							(mid -0.137521 0.162921)
							(end -0.1016 0.1778)
						)
						(arc
							(start 0.1016 0.1778)
							(mid 0.137521 0.162921)
							(end 0.1524 0.127)
						)
					)
					(width 0)
					(fill yes)
				)
			)
		)
		(pad "2" smd custom
			(at 0 0.2794 180)
			(size 0.0762 0.0762)
			(layers "F.Cu" "F.Mask" "F.Paste")
			(net "GND")
			(options
				(clearance outline)
				(anchor circle)
			)
			(primitives
				(gr_poly
					(pts
						(arc
							(start 0.1524 -0.127)
							(mid 0.137521 -0.162921)
							(end 0.1016 -0.1778)
						)
						(arc
							(start -0.1016 -0.1778)
							(mid -0.137521 -0.162921)
							(end -0.1524 -0.127)
						)
						(arc
							(start -0.1524 0.127)
							(mid -0.137521 0.162921)
							(end -0.1016 0.1778)
						)
						(arc
							(start 0.1016 0.1778)
							(mid 0.137521 0.162921)
							(end 0.1524 0.127)
						)
					)
					(width 0)
					(fill yes)
				)
			)
		)
	)
	(footprint ""
		(layer "F.Cu")
		(at 217.43797 -69.088)
		(property "Reference" "R12"
			(at 0 0 0)
			(layer "F.SilkS")
			(hide yes)
			(effects
				(font
					(size 1.27 1.27)
				)
			)
		)
		(property "Value" "10KR2F-2-GP"
			(at 0.064008 -3.993896 0)
			(unlocked yes)
			(layer "F.Fab")
			(hide yes)
			(effects
				(font
					(size 1.016 1.016)
					(thickness 0.1524)
				)
			)
		)
		(property "Device Type" "R402H16"
			(at 0.064008 -5.517896 0)
			(unlocked yes)
			(layer "F.Fab")
			(hide yes)
			(effects
				(font
					(size 1.016 1.016)
					(thickness 0.1524)
				)
			)
		)
		(duplicate_pad_numbers_are_jumpers no)
		(fp_line
			(start -0.508 -0.9398)
			(end -0.508 0.9398)
			(stroke
				(width 0.1524)
				(type default)
			)
			(layer "F.SilkS")
		)
		(fp_line
			(start 0.508 -0.9398)
			(end -0.508 -0.9398)
			(stroke
				(width 0.1524)
				(type default)
			)
			(layer "F.SilkS")
		)
		(fp_rect
			(start -0.508 0.9398)
			(end 0.508 -0.9398)
			(stroke
				(width 0)
				(type default)
			)
			(fill no)
			(layer "F.CrtYd")
		)
		(fp_rect
			(start -0.508 0.9398)
			(end 0.508 -0.9398)
			(stroke
				(width 0)
				(type default)
			)
			(fill no)
			(layer "F.Fab")
		)
		(pad "1" smd custom
			(at 0 -0.4445)
			(size 0.1397 0.1397)
			(layers "F.Cu" "F.Mask" "F.Paste")
			(net "SVR_ID1")
			(options
				(clearance outline)
				(anchor circle)
			)
			(primitives
				(gr_poly
					(pts
						(arc
							(start -0.1778 -0.2794)
							(mid -0.249642 -0.249642)
							(end -0.2794 -0.1778)
						)
						(arc
							(start -0.2794 0.1778)
							(mid -0.249642 0.249642)
							(end -0.1778 0.2794)
						)
						(arc
							(start 0.1778 0.2794)
							(mid 0.249642 0.249642)
							(end 0.2794 0.1778)
						)
						(arc
							(start 0.2794 -0.1778)
							(mid 0.249642 -0.249642)
							(end 0.1778 -0.2794)
						)
					)
					(width 0)
					(fill yes)
				)
			)
		)
		(pad "2" smd custom
			(at 0 0.4445)
			(size 0.1397 0.1397)
			(layers "F.Cu" "F.Mask" "F.Paste")
			(net "P3V3_STBY")
			(options
				(clearance outline)
				(anchor circle)
			)
			(primitives
				(gr_poly
					(pts
						(arc
							(start -0.1778 -0.2794)
							(mid -0.249642 -0.249642)
							(end -0.2794 -0.1778)
						)
						(arc
							(start -0.2794 0.1778)
							(mid -0.249642 0.249642)
							(end -0.1778 0.2794)
						)
						(arc
							(start 0.1778 0.2794)
							(mid 0.249642 0.249642)
							(end 0.2794 0.1778)
						)
						(arc
							(start 0.2794 -0.1778)
							(mid 0.249642 -0.249642)
							(end 0.1778 -0.2794)
						)
					)
					(width 0)
					(fill yes)
				)
			)
		)
	)
	(footprint ""
		(layer "F.Cu")
		(at 333.366872 -232.482136)
		(property "Reference" "R185"
			(at 0 0 0)
			(layer "F.SilkS")
			(hide yes)
			(effects
				(font
					(size 1.27 1.27)
				)
			)
		)
		(property "Value" "4K7R2F-GP"
			(at 0.064008 -3.993896 0)
			(unlocked yes)
			(layer "F.Fab")
			(hide yes)
			(effects
				(font
					(size 1.016 1.016)
					(thickness 0.1524)
				)
			)
		)
		(property "Device Type" "R402H16"
			(at 0.064008 -5.517896 0)
			(unlocked yes)
			(layer "F.Fab")
			(hide yes)
			(effects
				(font
					(size 1.016 1.016)
					(thickness 0.1524)
				)
			)
		)
		(duplicate_pad_numbers_are_jumpers no)
		(fp_line
			(start -0.508 -0.9398)
			(end -0.508 0.9398)
			(stroke
				(width 0.1524)
				(type default)
			)
			(layer "F.SilkS")
		)
		(fp_line
			(start 0.508 -0.9398)
			(end -0.508 -0.9398)
			(stroke
				(width 0.1524)
				(type default)
			)
			(layer "F.SilkS")
		)
		(fp_rect
			(start -0.508 0.9398)
			(end 0.508 -0.9398)
			(stroke
				(width 0)
				(type default)
			)
			(fill no)
			(layer "F.CrtYd")
		)
		(fp_rect
			(start -0.508 0.9398)
			(end 0.508 -0.9398)
			(stroke
				(width 0)
				(type default)
			)
			(fill no)
			(layer "F.Fab")
		)
		(pad "1" smd custom
			(at 0 -0.4445)
			(size 0.1397 0.1397)
			(layers "F.Cu" "F.Mask" "F.Paste")
			(net "P3V3_STBY")
			(options
				(clearance outline)
				(anchor circle)
			)
			(primitives
				(gr_poly
					(pts
						(arc
							(start -0.1778 -0.2794)
							(mid -0.249642 -0.249642)
							(end -0.2794 -0.1778)
						)
						(arc
							(start -0.2794 0.1778)
							(mid -0.249642 0.249642)
							(end -0.1778 0.2794)
						)
						(arc
							(start 0.1778 0.2794)
							(mid 0.249642 0.249642)
							(end 0.2794 0.1778)
						)
						(arc
							(start 0.2794 -0.1778)
							(mid 0.249642 -0.249642)
							(end 0.1778 -0.2794)
						)
					)
					(width 0)
					(fill yes)
				)
			)
		)
		(pad "2" smd custom
			(at 0 0.4445)
			(size 0.1397 0.1397)
			(layers "F.Cu" "F.Mask" "F.Paste")
			(net "VOL_SEN_ALERT")
			(options
				(clearance outline)
				(anchor circle)
			)
			(primitives
				(gr_poly
					(pts
						(arc
							(start -0.1778 -0.2794)
							(mid -0.249642 -0.249642)
							(end -0.2794 -0.1778)
						)
						(arc
							(start -0.2794 0.1778)
							(mid -0.249642 0.249642)
							(end -0.1778 0.2794)
						)
						(arc
							(start 0.1778 0.2794)
							(mid 0.249642 0.249642)
							(end 0.2794 0.1778)
						)
						(arc
							(start 0.2794 -0.1778)
							(mid 0.249642 -0.249642)
							(end 0.1778 -0.2794)
						)
					)
					(width 0)
					(fill yes)
				)
			)
		)
	)
	(footprint ""
		(layer "F.Cu")
		(at 24.842216 -204.17028)
		(property "Reference" "TP168"
			(at 0 0 0)
			(layer "F.SilkS")
			(hide yes)
			(effects
				(font
					(size 1.27 1.27)
				)
			)
		)
		(property "Value" "TPAD32-GP"
			(at 0 -3.166364 0)
			(unlocked yes)
			(layer "F.Fab")
			(hide yes)
			(effects
				(font
					(size 1.016 1.016)
					(thickness 0.1524)
				)
			)
		)
		(property "Device Type" "TPAD32"
			(at 0 -4.690618 0)
			(unlocked yes)
			(layer "F.Fab")
			(hide yes)
			(effects
				(font
					(size 1.016 1.016)
					(thickness 0.1524)
				)
			)
		)
		(duplicate_pad_numbers_are_jumpers no)
		(fp_poly
			(pts
				(arc
					(start 0.4064 0)
					(mid -0.4064 0)
					(end 0.4064 0)
				)
			)
			(stroke
				(width 0)
				(type default)
			)
			(fill no)
			(layer "F.CrtYd")
		)
		(fp_poly
			(pts
				(arc
					(start 0.7112 0)
					(mid -0.7112 0)
					(end 0.7112 0)
				)
			)
			(stroke
				(width 0)
				(type default)
			)
			(fill no)
			(layer "F.Fab")
		)
		(pad "1" smd circle
			(at 0 0)
			(size 0.8128 0.8128)
			(layers "F.Cu" "F.Mask" "F.Paste")
			(net "VOL_SEN_ALERT_U17")
		)
	)
	(footprint ""
		(layer "F.Cu")
		(at 43.5102 -119.4562 90)
		(property "Reference" "U186"
			(at 0 0 90)
			(layer "F.SilkS")
			(hide yes)
			(effects
				(font
					(size 1.27 1.27)
				)
			)
		)
		(property "Value" "TXS0102DCUR-1-GP"
			(at 0 -11.1252 90)
			(unlocked yes)
			(layer "F.Fab")
			(hide yes)
			(effects
				(font
					(size 1.016 1.016)
					(thickness 0.1524)
				)
			)
		)
		(property "Device Type" "SSOIC8-4H36"
			(at 0 -12.6492 90)
			(unlocked yes)
			(layer "F.Fab")
			(hide yes)
			(effects
				(font
					(size 1.016 1.016)
					(thickness 0.1524)
				)
			)
		)
		(duplicate_pad_numbers_are_jumpers no)
		(fp_line
			(start 1.2573 -2.1844)
			(end 1.2573 2.1844)
			(stroke
				(width 0.1524)
				(type default)
			)
			(layer "F.SilkS")
		)
		(fp_line
			(start -1.2573 -2.1844)
			(end 1.2573 -2.1844)
			(stroke
				(width 0.1524)
				(type default)
			)
			(layer "F.SilkS")
		)
		(fp_line
			(start -1.2192 -0.3556)
			(end -0.9017 -0.0381)
			(stroke
				(width 0.1524)
				(type default)
			)
			(layer "F.SilkS")
		)
		(fp_line
			(start -1.2573 -0.3556)
			(end -1.2192 -0.3556)
			(stroke
				(width 0.1524)
				(type default)
			)
			(layer "F.SilkS")
		)
		(fp_line
			(start -0.9017 -0.0381)
			(end -1.2065 0.2667)
			(stroke
				(width 0.1524)
				(type default)
			)
			(layer "F.SilkS")
		)
		(fp_line
			(start -1.2065 0.2667)
			(end -1.27 0.2667)
			(stroke
				(width 0.1524)
				(type default)
			)
			(layer "F.SilkS")
		)
		(fp_line
			(start -1.2954 0.4572)
			(end -1.2954 2.159)
			(stroke
				(width 0.4064)
				(type default)
			)
			(layer "F.SilkS")
		)
		(fp_line
			(start 1.2573 2.1844)
			(end -1.2573 2.1844)
			(stroke
				(width 0.1524)
				(type default)
			)
			(layer "F.SilkS")
		)
		(fp_line
			(start -1.2573 2.1844)
			(end -1.2573 -2.1844)
			(stroke
				(width 0.1524)
				(type default)
			)
			(layer "F.SilkS")
		)
		(fp_poly
			(pts
				(xy -1.5113 2.4384) (xy 1.5113 2.4384) (xy 1.5113 -2.4384) (xy -1.5113 -2.4384)
			)
			(stroke
				(width 0)
				(type default)
			)
			(fill no)
			(layer "F.CrtYd")
		)
		(fp_poly
			(pts
				(xy -1.5113 -2.4384) (xy 1.5113 -2.4384) (xy 1.5113 2.4384) (xy -1.5113 2.4384)
			)
			(stroke
				(width 0)
				(type default)
			)
			(fill no)
			(layer "F.Fab")
		)
		(pad "1" smd rect
			(at -0.75057 1.1684 90)
			(size 0.3048 1.524)
			(layers "F.Cu" "F.Mask" "F.Paste")
			(net "SAS_R_SDBRX")
		)
		(pad "2" smd rect
			(at -0.25019 1.1684 90)
			(size 0.3048 1.524)
			(layers "F.Cu" "F.Mask" "F.Paste")
			(net "GND")
		)
		(pad "3" smd rect
			(at 0.25019 1.1684 90)
			(size 0.3048 1.524)
			(layers "F.Cu" "F.Mask" "F.Paste")
			(net "P1V8_E")
		)
		(pad "4" smd rect
			(at 0.75057 1.1684 90)
			(size 0.3048 1.524)
			(layers "F.Cu" "F.Mask" "F.Paste")
			(net "SDB_RX_R")
		)
		(pad "5" smd rect
			(at 0.75057 -1.1684 90)
			(size 0.3048 1.524)
			(layers "F.Cu" "F.Mask" "F.Paste")
			(net "SDB_TX_R")
		)
		(pad "6" smd rect
			(at 0.25019 -1.1684 90)
			(size 0.3048 1.524)
			(layers "F.Cu" "F.Mask" "F.Paste")
			(net "SDB_UART_EN")
		)
		(pad "7" smd rect
			(at -0.25019 -1.1684 90)
			(size 0.3048 1.524)
			(layers "F.Cu" "F.Mask" "F.Paste")
			(net "P3V3_STBY")
		)
		(pad "8" smd rect
			(at -0.75057 -1.1684 90)
			(size 0.3048 1.524)
			(layers "F.Cu" "F.Mask" "F.Paste")
			(net "SAS_R_SDBTX")
		)
	)
)
